(kicad_pcb
	(version 20260206)
	(generator "pcbnew")
	(generator_version "10.0")
	(general
		(thickness 1.6)
		(legacy_teardrops no)
	)
	(paper "A4")
	(title_block
		(title "04192023_DAF0TMB3IC0_F0TG_MB_C_brd_V02_OCP.brd")
		(comment 1 "Grand Teton / footprints 694-700 of 8354")
	)
	(layers
		(0 "F.Cu" signal "TOP")
		(4 "In1.Cu" signal "GND")
		(6 "In2.Cu" signal "IN1")
		(8 "In3.Cu" signal "GND1")
		(10 "In4.Cu" signal "IN2")
		(12 "In5.Cu" signal "GND2")
		(14 "In6.Cu" signal "IN3")
		(16 "In7.Cu" signal "GND3")
		(18 "In8.Cu" signal "VCC")
		(20 "In9.Cu" signal "VCC1")
		(22 "In10.Cu" signal "GND4")
		(24 "In11.Cu" signal "IN4")
		(26 "In12.Cu" signal "GND5")
		(28 "In13.Cu" signal "IN5")
		(30 "In14.Cu" signal "GND6")
		(32 "In15.Cu" signal "IN6")
		(34 "In16.Cu" signal "GND7")
		(2 "B.Cu" signal "BOTTOM")
		(9 "F.Adhes" user "F.Adhesive")
		(11 "B.Adhes" user "B.Adhesive")
		(13 "F.Paste" user "Package Geometry/Pastemask Top")
		(15 "B.Paste" user "Package Geometry/Pastemask Bottom")
		(5 "F.SilkS" user "Ref Des/Silkscreen Top")
		(7 "B.SilkS" user "Ref Des/Silkscreen Bottom")
		(1 "F.Mask" user "Board Geometry/Soldermask Top")
		(3 "B.Mask" user "Board Geometry/Soldermask Bottom")
		(17 "Dwgs.User" user "User.Drawings")
		(19 "Cmts.User" user "User.Comments")
		(21 "Eco1.User" user "User.Eco1")
		(23 "Eco2.User" user "User.Eco2")
		(25 "Edge.Cuts" user "Board Geometry/Outline")
		(27 "Margin" user)
		(31 "F.CrtYd" user "Package Geometry/Place Bound Top")
		(29 "B.CrtYd" user "Package Geometry/Place Bound Bottom")
		(35 "F.Fab" user "Ref Des/Assembly Top")
		(33 "B.Fab" user "Ref Des/Assembly Bottom")
	)
	(footprint ""
		(layer "F.Cu")
		(at 226.0981 -404.020782)
		(property "Reference" "PC2224"
			(at 0 0 0)
			(layer "F.SilkS")
			(hide yes)
			(effects
				(font
					(size 1.27 1.27)
				)
			)
		)
		(property "Value" ""
			(at 0 0 0)
			(layer "F.Fab")
			(effects
				(font
					(size 1.27 1.27)
				)
			)
		)
		(duplicate_pad_numbers_are_jumpers no)
		(fp_line
			(start -0.7874 -0.4064)
			(end 0.7874 -0.4064)
			(stroke
				(width 0.1524)
				(type default)
			)
			(layer "F.SilkS")
		)
		(fp_line
			(start -0.7874 0.4064)
			(end -0.7874 -0.4064)
			(stroke
				(width 0.1524)
				(type default)
			)
			(layer "F.SilkS")
		)
		(fp_line
			(start 0.7874 -0.4064)
			(end 0.7874 0.4064)
			(stroke
				(width 0.1524)
				(type default)
			)
			(layer "F.SilkS")
		)
		(fp_line
			(start 0.7874 0.4064)
			(end -0.7874 0.4064)
			(stroke
				(width 0.1524)
				(type default)
			)
			(layer "F.SilkS")
		)
		(fp_line
			(start -0.67945 -0.305054)
			(end -0.12065 -0.305054)
			(stroke
				(width 0.1)
				(type default)
			)
			(layer "F.Fab")
		)
		(fp_line
			(start -0.67945 0.3048)
			(end -0.67945 -0.305054)
			(stroke
				(width 0.1)
				(type default)
			)
			(layer "F.Fab")
		)
		(fp_line
			(start -0.12065 -0.305054)
			(end -0.12065 -0.2794)
			(stroke
				(width 0.1)
				(type default)
			)
			(layer "F.Fab")
		)
		(fp_line
			(start -0.12065 -0.2794)
			(end 0.12065 -0.2794)
			(stroke
				(width 0.1)
				(type default)
			)
			(layer "F.Fab")
		)
		(fp_line
			(start -0.12065 0.2794)
			(end -0.12065 0.3048)
			(stroke
				(width 0.1)
				(type default)
			)
			(layer "F.Fab")
		)
		(fp_line
			(start -0.12065 0.3048)
			(end -0.67945 0.3048)
			(stroke
				(width 0.1)
				(type default)
			)
			(layer "F.Fab")
		)
		(fp_line
			(start 0.120396 0.2794)
			(end -0.12065 0.2794)
			(stroke
				(width 0.1)
				(type default)
			)
			(layer "F.Fab")
		)
		(fp_line
			(start 0.120396 0.3048)
			(end 0.120396 0.2794)
			(stroke
				(width 0.1)
				(type default)
			)
			(layer "F.Fab")
		)
		(fp_line
			(start 0.12065 -0.3048)
			(end 0.67945 -0.3048)
			(stroke
				(width 0.1)
				(type default)
			)
			(layer "F.Fab")
		)
		(fp_line
			(start 0.12065 -0.2794)
			(end 0.12065 -0.3048)
			(stroke
				(width 0.1)
				(type default)
			)
			(layer "F.Fab")
		)
		(fp_line
			(start 0.67945 -0.3048)
			(end 0.67945 0.3048)
			(stroke
				(width 0.1)
				(type default)
			)
			(layer "F.Fab")
		)
		(fp_line
			(start 0.67945 0.3048)
			(end 0.120396 0.3048)
			(stroke
				(width 0.1)
				(type default)
			)
			(layer "F.Fab")
		)
		(pad "1" smd circle
			(at -0.40005 0)
			(size 0 0)
			(layers "F.Cu" "F.Mask" "F.Paste")
			(net "HSC_ON")
		)
		(pad "2" smd circle
			(at 0.40005 0)
			(size 0 0)
			(layers "F.Cu" "F.Mask" "F.Paste")
			(net "AGND_HSC")
		)
	)
	(footprint ""
		(layer "F.Cu")
		(at 174.030894 -390.53008 180)
		(property "Reference" "R863"
			(at 0 0 180)
			(layer "F.SilkS")
			(hide yes)
			(effects
				(font
					(size 1.27 1.27)
				)
			)
		)
		(property "Value" ""
			(at 0 0 180)
			(layer "F.Fab")
			(effects
				(font
					(size 1.27 1.27)
				)
			)
		)
		(duplicate_pad_numbers_are_jumpers no)
		(fp_line
			(start 0.32512 0.175006)
			(end -0.32512 0.175006)
			(stroke
				(width 0.1)
				(type default)
			)
			(layer "F.Fab")
		)
		(fp_line
			(start 0.32512 -0.175006)
			(end 0.32512 0.175006)
			(stroke
				(width 0.1)
				(type default)
			)
			(layer "F.Fab")
		)
		(fp_line
			(start -0.32512 0.175006)
			(end -0.32512 -0.175006)
			(stroke
				(width 0.1)
				(type default)
			)
			(layer "F.Fab")
		)
		(fp_line
			(start -0.32512 -0.175006)
			(end 0.32512 -0.175006)
			(stroke
				(width 0.1)
				(type default)
			)
			(layer "F.Fab")
		)
		(pad "1" smd rect
			(at -0.2667 0 180)
			(size 0.3048 0.381)
			(layers "F.Cu" "F.Mask" "F.Paste")
			(net "RT_CPU1_P2_ADDR3")
		)
		(pad "2" smd rect
			(at 0.2667 0)
			(size 0.3048 0.381)
			(layers "F.Cu" "F.Mask" "F.Paste")
			(net "GND")
		)
	)
	(footprint ""
		(layer "F.Cu")
		(at 209.070956 -30.276292 90)
		(property "Reference" "R3624"
			(at 0 0 90)
			(layer "F.SilkS")
			(hide yes)
			(effects
				(font
					(size 1.27 1.27)
				)
			)
		)
		(property "Value" ""
			(at 0 0 90)
			(layer "F.Fab")
			(effects
				(font
					(size 1.27 1.27)
				)
			)
		)
		(duplicate_pad_numbers_are_jumpers no)
		(fp_line
			(start 0.7874 -0.4064)
			(end 0.7874 0.4064)
			(stroke
				(width 0.1524)
				(type default)
			)
			(layer "F.SilkS")
		)
		(fp_line
			(start -0.7874 -0.4064)
			(end 0.7874 -0.4064)
			(stroke
				(width 0.1524)
				(type default)
			)
			(layer "F.SilkS")
		)
		(fp_line
			(start 0.7874 0.4064)
			(end -0.7874 0.4064)
			(stroke
				(width 0.1524)
				(type default)
			)
			(layer "F.SilkS")
		)
		(fp_line
			(start -0.7874 0.4064)
			(end -0.7874 -0.4064)
			(stroke
				(width 0.1524)
				(type default)
			)
			(layer "F.SilkS")
		)
		(fp_line
			(start -0.12065 -0.305054)
			(end -0.12065 -0.2794)
			(stroke
				(width 0.1)
				(type default)
			)
			(layer "F.Fab")
		)
		(fp_line
			(start -0.67945 -0.305054)
			(end -0.12065 -0.305054)
			(stroke
				(width 0.1)
				(type default)
			)
			(layer "F.Fab")
		)
		(fp_line
			(start 0.67945 -0.3048)
			(end 0.67945 0.3048)
			(stroke
				(width 0.1)
				(type default)
			)
			(layer "F.Fab")
		)
		(fp_line
			(start 0.12065 -0.3048)
			(end 0.67945 -0.3048)
			(stroke
				(width 0.1)
				(type default)
			)
			(layer "F.Fab")
		)
		(fp_line
			(start 0.12065 -0.2794)
			(end 0.12065 -0.3048)
			(stroke
				(width 0.1)
				(type default)
			)
			(layer "F.Fab")
		)
		(fp_line
			(start -0.12065 -0.2794)
			(end 0.12065 -0.2794)
			(stroke
				(width 0.1)
				(type default)
			)
			(layer "F.Fab")
		)
		(fp_line
			(start 0.120396 0.2794)
			(end -0.12065 0.2794)
			(stroke
				(width 0.1)
				(type default)
			)
			(layer "F.Fab")
		)
		(fp_line
			(start -0.12065 0.2794)
			(end -0.12065 0.3048)
			(stroke
				(width 0.1)
				(type default)
			)
			(layer "F.Fab")
		)
		(fp_line
			(start 0.67945 0.3048)
			(end 0.120396 0.3048)
			(stroke
				(width 0.1)
				(type default)
			)
			(layer "F.Fab")
		)
		(fp_line
			(start 0.120396 0.3048)
			(end 0.120396 0.2794)
			(stroke
				(width 0.1)
				(type default)
			)
			(layer "F.Fab")
		)
		(fp_line
			(start -0.12065 0.3048)
			(end -0.67945 0.3048)
			(stroke
				(width 0.1)
				(type default)
			)
			(layer "F.Fab")
		)
		(fp_line
			(start -0.67945 0.3048)
			(end -0.67945 -0.305054)
			(stroke
				(width 0.1)
				(type default)
			)
			(layer "F.Fab")
		)
		(pad "1" smd circle
			(at -0.40005 0 90)
			(size 0 0)
			(layers "F.Cu" "F.Mask" "F.Paste")
			(net "P3V3_AUX")
		)
		(pad "2" smd circle
			(at 0.40005 0 90)
			(size 0 0)
			(layers "F.Cu" "F.Mask" "F.Paste")
			(net "INA230_5_A1")
		)
	)
	(footprint ""
		(layer "F.Cu")
		(at 314.66282 -334.993488 -90)
		(property "Reference" "PC112_C1P0_3"
			(at 0 0 270)
			(layer "F.SilkS")
			(hide yes)
			(effects
				(font
					(size 1.27 1.27)
				)
			)
		)
		(property "Value" ""
			(at 0 0 270)
			(layer "F.Fab")
			(effects
				(font
					(size 1.27 1.27)
				)
			)
		)
		(duplicate_pad_numbers_are_jumpers no)
		(fp_line
			(start -0.7874 0.4064)
			(end -0.7874 -0.4064)
			(stroke
				(width 0.1524)
				(type default)
			)
			(layer "F.SilkS")
		)
		(fp_line
			(start 0.7874 0.4064)
			(end -0.7874 0.4064)
			(stroke
				(width 0.1524)
				(type default)
			)
			(layer "F.SilkS")
		)
		(fp_line
			(start -0.7874 -0.4064)
			(end 0.7874 -0.4064)
			(stroke
				(width 0.1524)
				(type default)
			)
			(layer "F.SilkS")
		)
		(fp_line
			(start 0.7874 -0.4064)
			(end 0.7874 0.4064)
			(stroke
				(width 0.1524)
				(type default)
			)
			(layer "F.SilkS")
		)
		(fp_line
			(start -0.67945 0.3048)
			(end -0.67945 -0.305054)
			(stroke
				(width 0.1)
				(type default)
			)
			(layer "F.Fab")
		)
		(fp_line
			(start -0.12065 0.3048)
			(end -0.67945 0.3048)
			(stroke
				(width 0.1)
				(type default)
			)
			(layer "F.Fab")
		)
		(fp_line
			(start 0.120396 0.3048)
			(end 0.120396 0.2794)
			(stroke
				(width 0.1)
				(type default)
			)
			(layer "F.Fab")
		)
		(fp_line
			(start 0.67945 0.3048)
			(end 0.120396 0.3048)
			(stroke
				(width 0.1)
				(type default)
			)
			(layer "F.Fab")
		)
		(fp_line
			(start -0.12065 0.2794)
			(end -0.12065 0.3048)
			(stroke
				(width 0.1)
				(type default)
			)
			(layer "F.Fab")
		)
		(fp_line
			(start 0.120396 0.2794)
			(end -0.12065 0.2794)
			(stroke
				(width 0.1)
				(type default)
			)
			(layer "F.Fab")
		)
		(fp_line
			(start -0.12065 -0.2794)
			(end 0.12065 -0.2794)
			(stroke
				(width 0.1)
				(type default)
			)
			(layer "F.Fab")
		)
		(fp_line
			(start 0.12065 -0.2794)
			(end 0.12065 -0.3048)
			(stroke
				(width 0.1)
				(type default)
			)
			(layer "F.Fab")
		)
		(fp_line
			(start 0.12065 -0.3048)
			(end 0.67945 -0.3048)
			(stroke
				(width 0.1)
				(type default)
			)
			(layer "F.Fab")
		)
		(fp_line
			(start 0.67945 -0.3048)
			(end 0.67945 0.3048)
			(stroke
				(width 0.1)
				(type default)
			)
			(layer "F.Fab")
		)
		(fp_line
			(start -0.67945 -0.305054)
			(end -0.12065 -0.305054)
			(stroke
				(width 0.1)
				(type default)
			)
			(layer "F.Fab")
		)
		(fp_line
			(start -0.12065 -0.305054)
			(end -0.12065 -0.2794)
			(stroke
				(width 0.1)
				(type default)
			)
			(layer "F.Fab")
		)
		(pad "1" smd circle
			(at -0.40005 0 270)
			(size 0 0)
			(layers "F.Cu" "F.Mask" "F.Paste")
			(net "PVDDCR_CPU1_P0_PVCC")
		)
		(pad "2" smd circle
			(at 0.40005 0 270)
			(size 0 0)
			(layers "F.Cu" "F.Mask" "F.Paste")
			(net "GND")
		)
	)
	(footprint ""
		(layer "F.Cu")
		(at 59.18073 -351.578672 90)
		(property "Reference" "PC403_4"
			(at 0 0 90)
			(layer "F.SilkS")
			(hide yes)
			(effects
				(font
					(size 1.27 1.27)
				)
			)
		)
		(property "Value" ""
			(at 0 0 90)
			(layer "F.Fab")
			(effects
				(font
					(size 1.27 1.27)
				)
			)
		)
		(duplicate_pad_numbers_are_jumpers no)
		(fp_line
			(start 0.7874 -0.4064)
			(end 0.7874 0.4064)
			(stroke
				(width 0.1524)
				(type default)
			)
			(layer "F.SilkS")
		)
		(fp_line
			(start -0.7874 -0.4064)
			(end 0.7874 -0.4064)
			(stroke
				(width 0.1524)
				(type default)
			)
			(layer "F.SilkS")
		)
		(fp_line
			(start 0.7874 0.4064)
			(end -0.7874 0.4064)
			(stroke
				(width 0.1524)
				(type default)
			)
			(layer "F.SilkS")
		)
		(fp_line
			(start -0.7874 0.4064)
			(end -0.7874 -0.4064)
			(stroke
				(width 0.1524)
				(type default)
			)
			(layer "F.SilkS")
		)
		(fp_line
			(start -0.12065 -0.305054)
			(end -0.12065 -0.2794)
			(stroke
				(width 0.1)
				(type default)
			)
			(layer "F.Fab")
		)
		(fp_line
			(start -0.67945 -0.305054)
			(end -0.12065 -0.305054)
			(stroke
				(width 0.1)
				(type default)
			)
			(layer "F.Fab")
		)
		(fp_line
			(start 0.67945 -0.3048)
			(end 0.67945 0.3048)
			(stroke
				(width 0.1)
				(type default)
			)
			(layer "F.Fab")
		)
		(fp_line
			(start 0.12065 -0.3048)
			(end 0.67945 -0.3048)
			(stroke
				(width 0.1)
				(type default)
			)
			(layer "F.Fab")
		)
		(fp_line
			(start 0.12065 -0.2794)
			(end 0.12065 -0.3048)
			(stroke
				(width 0.1)
				(type default)
			)
			(layer "F.Fab")
		)
		(fp_line
			(start -0.12065 -0.2794)
			(end 0.12065 -0.2794)
			(stroke
				(width 0.1)
				(type default)
			)
			(layer "F.Fab")
		)
		(fp_line
			(start 0.120396 0.2794)
			(end -0.12065 0.2794)
			(stroke
				(width 0.1)
				(type default)
			)
			(layer "F.Fab")
		)
		(fp_line
			(start -0.12065 0.2794)
			(end -0.12065 0.3048)
			(stroke
				(width 0.1)
				(type default)
			)
			(layer "F.Fab")
		)
		(fp_line
			(start 0.67945 0.3048)
			(end 0.120396 0.3048)
			(stroke
				(width 0.1)
				(type default)
			)
			(layer "F.Fab")
		)
		(fp_line
			(start 0.120396 0.3048)
			(end 0.120396 0.2794)
			(stroke
				(width 0.1)
				(type default)
			)
			(layer "F.Fab")
		)
		(fp_line
			(start -0.12065 0.3048)
			(end -0.67945 0.3048)
			(stroke
				(width 0.1)
				(type default)
			)
			(layer "F.Fab")
		)
		(fp_line
			(start -0.67945 0.3048)
			(end -0.67945 -0.305054)
			(stroke
				(width 0.1)
				(type default)
			)
			(layer "F.Fab")
		)
		(pad "1" smd circle
			(at -0.40005 0 90)
			(size 0 0)
			(layers "F.Cu" "F.Mask" "F.Paste")
			(net "PVDDCR_CPU1_P1_VCCS")
		)
		(pad "2" smd circle
			(at 0.40005 0 90)
			(size 0 0)
			(layers "F.Cu" "F.Mask" "F.Paste")
			(net "GND")
		)
	)
	(footprint ""
		(layer "F.Cu")
		(at 32.272478 -16.099536 90)
		(property "Reference" "C690"
			(at 0 0 90)
			(layer "F.SilkS")
			(hide yes)
			(effects
				(font
					(size 1.27 1.27)
				)
			)
		)
		(property "Value" ""
			(at 0 0 90)
			(layer "F.Fab")
			(effects
				(font
					(size 1.27 1.27)
				)
			)
		)
		(duplicate_pad_numbers_are_jumpers no)
		(fp_line
			(start 0.299974 -0.150114)
			(end 0.299974 0.150114)
			(stroke
				(width 0.1)
				(type default)
			)
			(layer "F.Fab")
		)
		(fp_line
			(start -0.299974 -0.150114)
			(end 0.299974 -0.150114)
			(stroke
				(width 0.1)
				(type default)
			)
			(layer "F.Fab")
		)
		(fp_line
			(start 0.299974 0.150114)
			(end -0.299974 0.150114)
			(stroke
				(width 0.1)
				(type default)
			)
			(layer "F.Fab")
		)
		(fp_line
			(start -0.299974 0.150114)
			(end -0.299974 -0.150114)
			(stroke
				(width 0.1)
				(type default)
			)
			(layer "F.Fab")
		)
		(pad "1" smd rect
			(at -0.2667 0 90)
			(size 0.3048 0.381)
			(layers "F.Cu" "F.Mask" "F.Paste")
			(net "P5E_CPU1_G1_TX_C_DN<9>")
		)
		(pad "2" smd rect
			(at 0.2667 0 90)
			(size 0.3048 0.381)
			(layers "F.Cu" "F.Mask" "F.Paste")
			(net "P5E_CPU1_G1_TX_DN<9>")
		)
	)
	(footprint ""
		(layer "F.Cu")
		(at 220.98508 -106.35488)
		(property "Reference" "R1518"
			(at 0 0 0)
			(layer "F.SilkS")
			(hide yes)
			(effects
				(font
					(size 1.27 1.27)
				)
			)
		)
		(property "Value" ""
			(at 0 0 0)
			(layer "F.Fab")
			(effects
				(font
					(size 1.27 1.27)
				)
			)
		)
		(duplicate_pad_numbers_are_jumpers no)
		(fp_line
			(start -0.7874 -0.4064)
			(end 0.7874 -0.4064)
			(stroke
				(width 0.1524)
				(type default)
			)
			(layer "F.SilkS")
		)
		(fp_line
			(start -0.7874 0.4064)
			(end -0.7874 -0.4064)
			(stroke
				(width 0.1524)
				(type default)
			)
			(layer "F.SilkS")
		)
		(fp_line
			(start 0.7874 -0.4064)
			(end 0.7874 0.4064)
			(stroke
				(width 0.1524)
				(type default)
			)
			(layer "F.SilkS")
		)
		(fp_line
			(start 0.7874 0.4064)
			(end -0.7874 0.4064)
			(stroke
				(width 0.1524)
				(type default)
			)
			(layer "F.SilkS")
		)
		(fp_line
			(start -0.67945 -0.305054)
			(end -0.12065 -0.305054)
			(stroke
				(width 0.1)
				(type default)
			)
			(layer "F.Fab")
		)
		(fp_line
			(start -0.67945 0.3048)
			(end -0.67945 -0.305054)
			(stroke
				(width 0.1)
				(type default)
			)
			(layer "F.Fab")
		)
		(fp_line
			(start -0.12065 -0.305054)
			(end -0.12065 -0.2794)
			(stroke
				(width 0.1)
				(type default)
			)
			(layer "F.Fab")
		)
		(fp_line
			(start -0.12065 -0.2794)
			(end 0.12065 -0.2794)
			(stroke
				(width 0.1)
				(type default)
			)
			(layer "F.Fab")
		)
		(fp_line
			(start -0.12065 0.2794)
			(end -0.12065 0.3048)
			(stroke
				(width 0.1)
				(type default)
			)
			(layer "F.Fab")
		)
		(fp_line
			(start -0.12065 0.3048)
			(end -0.67945 0.3048)
			(stroke
				(width 0.1)
				(type default)
			)
			(layer "F.Fab")
		)
		(fp_line
			(start 0.120396 0.2794)
			(end -0.12065 0.2794)
			(stroke
				(width 0.1)
				(type default)
			)
			(layer "F.Fab")
		)
		(fp_line
			(start 0.120396 0.3048)
			(end 0.120396 0.2794)
			(stroke
				(width 0.1)
				(type default)
			)
			(layer "F.Fab")
		)
		(fp_line
			(start 0.12065 -0.3048)
			(end 0.67945 -0.3048)
			(stroke
				(width 0.1)
				(type default)
			)
			(layer "F.Fab")
		)
		(fp_line
			(start 0.12065 -0.2794)
			(end 0.12065 -0.3048)
			(stroke
				(width 0.1)
				(type default)
			)
			(layer "F.Fab")
		)
		(fp_line
			(start 0.67945 -0.3048)
			(end 0.67945 0.3048)
			(stroke
				(width 0.1)
				(type default)
			)
			(layer "F.Fab")
		)
		(fp_line
			(start 0.67945 0.3048)
			(end 0.120396 0.3048)
			(stroke
				(width 0.1)
				(type default)
			)
			(layer "F.Fab")
		)
		(pad "1" smd circle
			(at -0.40005 0)
			(size 0 0)
			(layers "F.Cu" "F.Mask" "F.Paste")
			(net "HP_LVC3_OCP_V3_1_PWRGD_R2")
		)
		(pad "2" smd circle
			(at 0.40005 0)
			(size 0 0)
			(layers "F.Cu" "F.Mask" "F.Paste")
			(net "OCP_V3_1_P3V3_R3_PWRGD")
		)
	)
)
